(kicad_pcb
	(version 20260206)
	(generator "pcbnew")
	(generator_version "10.0")
	(general
		(thickness 1.6)
		(legacy_teardrops no)
	)
	(paper "A4")
	(title_block
		(title "m-2 — Lightning_M.2_BRD.brd")
		(comment 1 "Lightning (Wiwynn / Facebook NVMe JBOF) / footprints 124-130 of 157")
	)
	(layers
		(0 "F.Cu" signal "TOP")
		(4 "In1.Cu" signal "L2GND")
		(6 "In2.Cu" signal "L3")
		(8 "In3.Cu" signal "L4GND")
		(10 "In4.Cu" signal "L5GND")
		(12 "In5.Cu" signal "L6")
		(14 "In6.Cu" signal "L7GND")
		(2 "B.Cu" signal "BOTTOM")
		(9 "F.Adhes" user "F.Adhesive")
		(11 "B.Adhes" user "B.Adhesive")
		(13 "F.Paste" user "Package Geometry/Pastemask Top")
		(15 "B.Paste" user "Package Geometry/Pastemask Bottom")
		(5 "F.SilkS" user "Ref Des/Silkscreen Top")
		(7 "B.SilkS" user "Ref Des/Silkscreen Bottom")
		(1 "F.Mask" user "Board Geometry/Soldermask Top")
		(3 "B.Mask" user "Board Geometry/Soldermask Bottom")
		(17 "Dwgs.User" user "User.Drawings")
		(19 "Cmts.User" user "User.Comments")
		(21 "Eco1.User" user "User.Eco1")
		(23 "Eco2.User" user "User.Eco2")
		(25 "Edge.Cuts" user "Board Geometry/Outline")
		(27 "Margin" user)
		(31 "F.CrtYd" user "Package Geometry/Place Bound Top")
		(29 "B.CrtYd" user "Package Geometry/Place Bound Bottom")
		(35 "F.Fab" user "Ref Des/Assembly Top")
		(33 "B.Fab" user "Ref Des/Assembly Bottom")
	)
	(footprint ""
		(layer "B.Cu")
		(at 59.260994 -42.164 180)
		(property "Reference" "R6"
			(at 0 0 0)
			(layer "B.SilkS")
			(hide yes)
			(effects
				(font
					(size 1.27 1.27)
				)
				(justify mirror)
			)
		)
		(property "Value" "4K7R2F-GP"
			(at -0.064008 -3.993896 180)
			(unlocked yes)
			(layer "B.Fab")
			(hide yes)
			(effects
				(font
					(size 1.016 1.016)
					(thickness 0.1524)
				)
				(justify mirror)
			)
		)
		(property "Device Type" "R402H16"
			(at -0.064008 -5.517896 180)
			(unlocked yes)
			(layer "B.Fab")
			(hide yes)
			(effects
				(font
					(size 1.016 1.016)
					(thickness 0.1524)
				)
				(justify mirror)
			)
		)
		(duplicate_pad_numbers_are_jumpers no)
		(fp_line
			(start 0.508 -0.9398)
			(end 0.508 0.9398)
			(stroke
				(width 0.1524)
				(type default)
			)
			(layer "B.SilkS")
		)
		(fp_line
			(start -0.508 -0.9398)
			(end 0.508 -0.9398)
			(stroke
				(width 0.1524)
				(type default)
			)
			(layer "B.SilkS")
		)
		(fp_rect
			(start 0.508 0.9398)
			(end -0.508 -0.9398)
			(stroke
				(width 0)
				(type default)
			)
			(fill no)
			(layer "B.CrtYd")
		)
		(fp_rect
			(start 0.508 0.9398)
			(end -0.508 -0.9398)
			(stroke
				(width 0)
				(type default)
			)
			(fill no)
			(layer "B.Fab")
		)
		(pad "1" smd custom
			(at 0 -0.4445)
			(size 0.1397 0.1397)
			(layers "B.Cu" "B.Mask" "B.Paste")
			(net "P3V3_DPB")
			(options
				(clearance outline)
				(anchor circle)
			)
			(primitives
				(gr_poly
					(pts
						(arc
							(start -0.1778 0.2794)
							(mid -0.249642 0.249642)
							(end -0.2794 0.1778)
						)
						(arc
							(start -0.2794 -0.1778)
							(mid -0.249642 -0.249642)
							(end -0.1778 -0.2794)
						)
						(arc
							(start 0.1778 -0.2794)
							(mid 0.249642 -0.249642)
							(end 0.2794 -0.1778)
						)
						(arc
							(start 0.2794 0.1778)
							(mid 0.249642 0.249642)
							(end 0.1778 0.2794)
						)
					)
					(width 0)
					(fill yes)
				)
			)
		)
		(pad "2" smd custom
			(at 0 0.4445)
			(size 0.1397 0.1397)
			(layers "B.Cu" "B.Mask" "B.Paste")
			(net "Z50_TEMP_1_A2")
			(options
				(clearance outline)
				(anchor circle)
			)
			(primitives
				(gr_poly
					(pts
						(arc
							(start -0.1778 0.2794)
							(mid -0.249642 0.249642)
							(end -0.2794 0.1778)
						)
						(arc
							(start -0.2794 -0.1778)
							(mid -0.249642 -0.249642)
							(end -0.1778 -0.2794)
						)
						(arc
							(start 0.1778 -0.2794)
							(mid 0.249642 -0.249642)
							(end 0.2794 -0.1778)
						)
						(arc
							(start 0.2794 0.1778)
							(mid 0.249642 0.249642)
							(end 0.1778 0.2794)
						)
					)
					(width 0)
					(fill yes)
				)
			)
		)
	)
	(footprint ""
		(layer "B.Cu")
		(at 58.244994 -38.354)
		(property "Reference" "R12"
			(at 0 0 0)
			(layer "B.SilkS")
			(hide yes)
			(effects
				(font
					(size 1.27 1.27)
				)
				(justify mirror)
			)
		)
		(property "Value" "4K7R2F-GP"
			(at -0.064008 -3.993896 0)
			(unlocked yes)
			(layer "B.Fab")
			(hide yes)
			(effects
				(font
					(size 1.016 1.016)
					(thickness 0.1524)
				)
				(justify mirror)
			)
		)
		(property "Device Type" "R402H16"
			(at -0.064008 -5.517896 0)
			(unlocked yes)
			(layer "B.Fab")
			(hide yes)
			(effects
				(font
					(size 1.016 1.016)
					(thickness 0.1524)
				)
				(justify mirror)
			)
		)
		(duplicate_pad_numbers_are_jumpers no)
		(fp_line
			(start -0.508 -0.9398)
			(end 0.508 -0.9398)
			(stroke
				(width 0.1524)
				(type default)
			)
			(layer "B.SilkS")
		)
		(fp_line
			(start 0.508 -0.9398)
			(end 0.508 0.9398)
			(stroke
				(width 0.1524)
				(type default)
			)
			(layer "B.SilkS")
		)
		(fp_rect
			(start 0.508 0.9398)
			(end -0.508 -0.9398)
			(stroke
				(width 0)
				(type default)
			)
			(fill no)
			(layer "B.CrtYd")
		)
		(fp_rect
			(start 0.508 0.9398)
			(end -0.508 -0.9398)
			(stroke
				(width 0)
				(type default)
			)
			(fill no)
			(layer "B.Fab")
		)
		(pad "1" smd custom
			(at 0 -0.4445 180)
			(size 0.1397 0.1397)
			(layers "B.Cu" "B.Mask" "B.Paste")
			(net "Z50_TEMP_1_A0")
			(options
				(clearance outline)
				(anchor circle)
			)
			(primitives
				(gr_poly
					(pts
						(arc
							(start -0.1778 0.2794)
							(mid -0.249642 0.249642)
							(end -0.2794 0.1778)
						)
						(arc
							(start -0.2794 -0.1778)
							(mid -0.249642 -0.249642)
							(end -0.1778 -0.2794)
						)
						(arc
							(start 0.1778 -0.2794)
							(mid 0.249642 -0.249642)
							(end 0.2794 -0.1778)
						)
						(arc
							(start 0.2794 0.1778)
							(mid 0.249642 0.249642)
							(end 0.1778 0.2794)
						)
					)
					(width 0)
					(fill yes)
				)
			)
		)
		(pad "2" smd custom
			(at 0 0.4445 180)
			(size 0.1397 0.1397)
			(layers "B.Cu" "B.Mask" "B.Paste")
			(net "GND")
			(options
				(clearance outline)
				(anchor circle)
			)
			(primitives
				(gr_poly
					(pts
						(arc
							(start -0.1778 0.2794)
							(mid -0.249642 0.249642)
							(end -0.2794 0.1778)
						)
						(arc
							(start -0.2794 -0.1778)
							(mid -0.249642 -0.249642)
							(end -0.1778 -0.2794)
						)
						(arc
							(start 0.1778 -0.2794)
							(mid 0.249642 -0.249642)
							(end 0.2794 -0.1778)
						)
						(arc
							(start 0.2794 0.1778)
							(mid 0.249642 0.249642)
							(end 0.1778 0.2794)
						)
					)
					(width 0)
					(fill yes)
				)
			)
		)
	)
	(footprint ""
		(layer "B.Cu")
		(at 28.829 -86.233)
		(property "Reference" "R50"
			(at 0 0 0)
			(layer "B.SilkS")
			(hide yes)
			(effects
				(font
					(size 1.27 1.27)
				)
				(justify mirror)
			)
		)
		(property "Value" "47KR2F-GP"
			(at -0.064008 -3.993896 0)
			(unlocked yes)
			(layer "B.Fab")
			(hide yes)
			(effects
				(font
					(size 1.016 1.016)
					(thickness 0.1524)
				)
				(justify mirror)
			)
		)
		(property "Device Type" "R402H16"
			(at -0.064008 -5.517896 0)
			(unlocked yes)
			(layer "B.Fab")
			(hide yes)
			(effects
				(font
					(size 1.016 1.016)
					(thickness 0.1524)
				)
				(justify mirror)
			)
		)
		(duplicate_pad_numbers_are_jumpers no)
		(fp_line
			(start -0.508 -0.9398)
			(end 0.508 -0.9398)
			(stroke
				(width 0.1524)
				(type default)
			)
			(layer "B.SilkS")
		)
		(fp_line
			(start 0.508 -0.9398)
			(end 0.508 0.9398)
			(stroke
				(width 0.1524)
				(type default)
			)
			(layer "B.SilkS")
		)
		(fp_rect
			(start 0.508 0.9398)
			(end -0.508 -0.9398)
			(stroke
				(width 0)
				(type default)
			)
			(fill no)
			(layer "B.CrtYd")
		)
		(fp_rect
			(start 0.508 0.9398)
			(end -0.508 -0.9398)
			(stroke
				(width 0)
				(type default)
			)
			(fill no)
			(layer "B.Fab")
		)
		(pad "1" smd custom
			(at 0 -0.4445 180)
			(size 0.1397 0.1397)
			(layers "B.Cu" "B.Mask" "B.Paste")
			(net "P3V3_DPB")
			(options
				(clearance outline)
				(anchor circle)
			)
			(primitives
				(gr_poly
					(pts
						(arc
							(start -0.1778 0.2794)
							(mid -0.249642 0.249642)
							(end -0.2794 0.1778)
						)
						(arc
							(start -0.2794 -0.1778)
							(mid -0.249642 -0.249642)
							(end -0.1778 -0.2794)
						)
						(arc
							(start 0.1778 -0.2794)
							(mid 0.249642 -0.249642)
							(end 0.2794 -0.1778)
						)
						(arc
							(start 0.2794 0.1778)
							(mid 0.249642 0.249642)
							(end 0.1778 0.2794)
						)
					)
					(width 0)
					(fill yes)
				)
			)
		)
		(pad "2" smd custom
			(at 0 0.4445 180)
			(size 0.1397 0.1397)
			(layers "B.Cu" "B.Mask" "B.Paste")
			(net "Z50_SMB_CLK")
			(options
				(clearance outline)
				(anchor circle)
			)
			(primitives
				(gr_poly
					(pts
						(arc
							(start -0.1778 0.2794)
							(mid -0.249642 0.249642)
							(end -0.2794 0.1778)
						)
						(arc
							(start -0.2794 -0.1778)
							(mid -0.249642 -0.249642)
							(end -0.1778 -0.2794)
						)
						(arc
							(start 0.1778 -0.2794)
							(mid 0.249642 -0.249642)
							(end 0.2794 -0.1778)
						)
						(arc
							(start 0.2794 0.1778)
							(mid 0.249642 0.249642)
							(end 0.1778 0.2794)
						)
					)
					(width 0)
					(fill yes)
				)
			)
		)
	)
	(footprint ""
		(layer "B.Cu")
		(at 27.686 -86.233)
		(property "Reference" "R51"
			(at 0 0 0)
			(layer "B.SilkS")
			(hide yes)
			(effects
				(font
					(size 1.27 1.27)
				)
				(justify mirror)
			)
		)
		(property "Value" "47KR2F-GP"
			(at -0.064008 -3.993896 0)
			(unlocked yes)
			(layer "B.Fab")
			(hide yes)
			(effects
				(font
					(size 1.016 1.016)
					(thickness 0.1524)
				)
				(justify mirror)
			)
		)
		(property "Device Type" "R402H16"
			(at -0.064008 -5.517896 0)
			(unlocked yes)
			(layer "B.Fab")
			(hide yes)
			(effects
				(font
					(size 1.016 1.016)
					(thickness 0.1524)
				)
				(justify mirror)
			)
		)
		(duplicate_pad_numbers_are_jumpers no)
		(fp_line
			(start -0.508 -0.9398)
			(end 0.508 -0.9398)
			(stroke
				(width 0.1524)
				(type default)
			)
			(layer "B.SilkS")
		)
		(fp_line
			(start 0.508 -0.9398)
			(end 0.508 0.9398)
			(stroke
				(width 0.1524)
				(type default)
			)
			(layer "B.SilkS")
		)
		(fp_rect
			(start 0.508 0.9398)
			(end -0.508 -0.9398)
			(stroke
				(width 0)
				(type default)
			)
			(fill no)
			(layer "B.CrtYd")
		)
		(fp_rect
			(start 0.508 0.9398)
			(end -0.508 -0.9398)
			(stroke
				(width 0)
				(type default)
			)
			(fill no)
			(layer "B.Fab")
		)
		(pad "1" smd custom
			(at 0 -0.4445 180)
			(size 0.1397 0.1397)
			(layers "B.Cu" "B.Mask" "B.Paste")
			(net "P3V3_DPB")
			(options
				(clearance outline)
				(anchor circle)
			)
			(primitives
				(gr_poly
					(pts
						(arc
							(start -0.1778 0.2794)
							(mid -0.249642 0.249642)
							(end -0.2794 0.1778)
						)
						(arc
							(start -0.2794 -0.1778)
							(mid -0.249642 -0.249642)
							(end -0.1778 -0.2794)
						)
						(arc
							(start 0.1778 -0.2794)
							(mid 0.249642 -0.249642)
							(end 0.2794 -0.1778)
						)
						(arc
							(start 0.2794 0.1778)
							(mid 0.249642 0.249642)
							(end 0.1778 0.2794)
						)
					)
					(width 0)
					(fill yes)
				)
			)
		)
		(pad "2" smd custom
			(at 0 0.4445 180)
			(size 0.1397 0.1397)
			(layers "B.Cu" "B.Mask" "B.Paste")
			(net "Z50_SMB_DATA")
			(options
				(clearance outline)
				(anchor circle)
			)
			(primitives
				(gr_poly
					(pts
						(arc
							(start -0.1778 0.2794)
							(mid -0.249642 0.249642)
							(end -0.2794 0.1778)
						)
						(arc
							(start -0.2794 -0.1778)
							(mid -0.249642 -0.249642)
							(end -0.1778 -0.2794)
						)
						(arc
							(start 0.1778 -0.2794)
							(mid 0.249642 -0.249642)
							(end 0.2794 -0.1778)
						)
						(arc
							(start 0.2794 0.1778)
							(mid 0.249642 0.249642)
							(end 0.1778 0.2794)
						)
					)
					(width 0)
					(fill yes)
				)
			)
		)
	)
	(footprint ""
		(layer "B.Cu")
		(at 25.527 -77.216)
		(property "Reference" "R64"
			(at 0 0 0)
			(layer "B.SilkS")
			(hide yes)
			(effects
				(font
					(size 1.27 1.27)
				)
				(justify mirror)
			)
		)
		(property "Value" "0R2J-2-GP"
			(at -0.064008 -3.993896 0)
			(unlocked yes)
			(layer "B.Fab")
			(hide yes)
			(effects
				(font
					(size 1.016 1.016)
					(thickness 0.1524)
				)
				(justify mirror)
			)
		)
		(property "Device Type" "R402H16"
			(at -0.064008 -5.517896 0)
			(unlocked yes)
			(layer "B.Fab")
			(hide yes)
			(effects
				(font
					(size 1.016 1.016)
					(thickness 0.1524)
				)
				(justify mirror)
			)
		)
		(duplicate_pad_numbers_are_jumpers no)
		(fp_line
			(start -0.508 -0.9398)
			(end 0.508 -0.9398)
			(stroke
				(width 0.1524)
				(type default)
			)
			(layer "B.SilkS")
		)
		(fp_line
			(start 0.508 -0.9398)
			(end 0.508 0.9398)
			(stroke
				(width 0.1524)
				(type default)
			)
			(layer "B.SilkS")
		)
		(fp_rect
			(start 0.508 0.9398)
			(end -0.508 -0.9398)
			(stroke
				(width 0)
				(type default)
			)
			(fill no)
			(layer "B.CrtYd")
		)
		(fp_rect
			(start 0.508 0.9398)
			(end -0.508 -0.9398)
			(stroke
				(width 0)
				(type default)
			)
			(fill no)
			(layer "B.Fab")
		)
		(pad "1" smd custom
			(at 0 -0.4445 180)
			(size 0.1397 0.1397)
			(layers "B.Cu" "B.Mask" "B.Paste")
			(net "Z50_SSD_B1_SMB_CLK_R")
			(options
				(clearance outline)
				(anchor circle)
			)
			(primitives
				(gr_poly
					(pts
						(arc
							(start -0.1778 0.2794)
							(mid -0.249642 0.249642)
							(end -0.2794 0.1778)
						)
						(arc
							(start -0.2794 -0.1778)
							(mid -0.249642 -0.249642)
							(end -0.1778 -0.2794)
						)
						(arc
							(start 0.1778 -0.2794)
							(mid 0.249642 -0.249642)
							(end 0.2794 -0.1778)
						)
						(arc
							(start 0.2794 0.1778)
							(mid 0.249642 0.249642)
							(end 0.1778 0.2794)
						)
					)
					(width 0)
					(fill yes)
				)
			)
		)
		(pad "2" smd custom
			(at 0 0.4445 180)
			(size 0.1397 0.1397)
			(layers "B.Cu" "B.Mask" "B.Paste")
			(net "Z50_SSD_B1_SMB_CLK")
			(options
				(clearance outline)
				(anchor circle)
			)
			(primitives
				(gr_poly
					(pts
						(arc
							(start -0.1778 0.2794)
							(mid -0.249642 0.249642)
							(end -0.2794 0.1778)
						)
						(arc
							(start -0.2794 -0.1778)
							(mid -0.249642 -0.249642)
							(end -0.1778 -0.2794)
						)
						(arc
							(start 0.1778 -0.2794)
							(mid 0.249642 -0.249642)
							(end 0.2794 -0.1778)
						)
						(arc
							(start 0.2794 0.1778)
							(mid 0.249642 0.249642)
							(end 0.1778 0.2794)
						)
					)
					(width 0)
					(fill yes)
				)
			)
		)
	)
	(footprint ""
		(layer "B.Cu")
		(at 71.755 -41.402)
		(property "Reference" "R23"
			(at 0 0 0)
			(layer "B.SilkS")
			(hide yes)
			(effects
				(font
					(size 1.27 1.27)
				)
				(justify mirror)
			)
		)
		(property "Value" "47KR2F-GP"
			(at -0.064008 -3.993896 0)
			(unlocked yes)
			(layer "B.Fab")
			(hide yes)
			(effects
				(font
					(size 1.016 1.016)
					(thickness 0.1524)
				)
				(justify mirror)
			)
		)
		(property "Device Type" "R402H16"
			(at -0.064008 -5.517896 0)
			(unlocked yes)
			(layer "B.Fab")
			(hide yes)
			(effects
				(font
					(size 1.016 1.016)
					(thickness 0.1524)
				)
				(justify mirror)
			)
		)
		(duplicate_pad_numbers_are_jumpers no)
		(fp_line
			(start -0.508 -0.9398)
			(end 0.508 -0.9398)
			(stroke
				(width 0.1524)
				(type default)
			)
			(layer "B.SilkS")
		)
		(fp_line
			(start 0.508 -0.9398)
			(end 0.508 0.9398)
			(stroke
				(width 0.1524)
				(type default)
			)
			(layer "B.SilkS")
		)
		(fp_rect
			(start 0.508 0.9398)
			(end -0.508 -0.9398)
			(stroke
				(width 0)
				(type default)
			)
			(fill no)
			(layer "B.CrtYd")
		)
		(fp_rect
			(start 0.508 0.9398)
			(end -0.508 -0.9398)
			(stroke
				(width 0)
				(type default)
			)
			(fill no)
			(layer "B.Fab")
		)
		(pad "1" smd custom
			(at 0 -0.4445 180)
			(size 0.1397 0.1397)
			(layers "B.Cu" "B.Mask" "B.Paste")
			(net "P3V3_DPB")
			(options
				(clearance outline)
				(anchor circle)
			)
			(primitives
				(gr_poly
					(pts
						(arc
							(start -0.1778 0.2794)
							(mid -0.249642 0.249642)
							(end -0.2794 0.1778)
						)
						(arc
							(start -0.2794 -0.1778)
							(mid -0.249642 -0.249642)
							(end -0.1778 -0.2794)
						)
						(arc
							(start 0.1778 -0.2794)
							(mid 0.249642 -0.249642)
							(end 0.2794 -0.1778)
						)
						(arc
							(start 0.2794 0.1778)
							(mid 0.249642 0.249642)
							(end 0.1778 0.2794)
						)
					)
					(width 0)
					(fill yes)
				)
			)
		)
		(pad "2" smd custom
			(at 0 0.4445 180)
			(size 0.1397 0.1397)
			(layers "B.Cu" "B.Mask" "B.Paste")
			(net "Z50_SSD_A_ACT#")
			(options
				(clearance outline)
				(anchor circle)
			)
			(primitives
				(gr_poly
					(pts
						(arc
							(start -0.1778 0.2794)
							(mid -0.249642 0.249642)
							(end -0.2794 0.1778)
						)
						(arc
							(start -0.2794 -0.1778)
							(mid -0.249642 -0.249642)
							(end -0.1778 -0.2794)
						)
						(arc
							(start 0.1778 -0.2794)
							(mid 0.249642 -0.249642)
							(end 0.2794 -0.1778)
						)
						(arc
							(start 0.2794 0.1778)
							(mid 0.249642 0.249642)
							(end 0.1778 0.2794)
						)
					)
					(width 0)
					(fill yes)
				)
			)
		)
	)
	(footprint ""
		(layer "B.Cu")
		(at 69.469 -40.386)
		(property "Reference" "U3"
			(at 0 0 0)
			(layer "B.SilkS")
			(hide yes)
			(effects
				(font
					(size 1.27 1.27)
				)
				(justify mirror)
			)
		)
		(property "Value" "74LVC1G32DC-1GP"
			(at 2.3368 -8.6868 0)
			(unlocked yes)
			(layer "B.Fab")
			(hide yes)
			(effects
				(font
					(size 1.016 1.016)
					(thickness 0.1524)
				)
				(justify mirror)
			)
		)
		(property "Device Type" "SC70-5H44"
			(at 2.3114 -10.414 0)
			(unlocked yes)
			(layer "B.Fab")
			(hide yes)
			(effects
				(font
					(size 1.016 1.016)
					(thickness 0.1524)
				)
				(justify mirror)
			)
		)
		(duplicate_pad_numbers_are_jumpers no)
		(fp_line
			(start -1.3843 -1.8034)
			(end -1.3843 -1.1176)
			(stroke
				(width 0.3302)
				(type default)
			)
			(layer "B.SilkS")
		)
		(fp_line
			(start -1.27 -1.7018)
			(end -1.27 1.7018)
			(stroke
				(width 0.1524)
				(type default)
			)
			(layer "B.SilkS")
		)
		(fp_line
			(start -1.27 1.7018)
			(end 1.27 1.7018)
			(stroke
				(width 0.1524)
				(type default)
			)
			(layer "B.SilkS")
		)
		(fp_line
			(start -0.6604 -1.8034)
			(end -1.3843 -1.8034)
			(stroke
				(width 0.3302)
				(type default)
			)
			(layer "B.SilkS")
		)
		(fp_line
			(start 1.27 -1.7018)
			(end -1.27 -1.7018)
			(stroke
				(width 0.1524)
				(type default)
			)
			(layer "B.SilkS")
		)
		(fp_line
			(start 1.27 1.7018)
			(end 1.27 -1.7018)
			(stroke
				(width 0.1524)
				(type default)
			)
			(layer "B.SilkS")
		)
		(fp_rect
			(start 1.524 1.9558)
			(end -1.524 -1.9558)
			(stroke
				(width 0)
				(type default)
			)
			(fill no)
			(layer "B.CrtYd")
		)
		(fp_poly
			(pts
				(xy 1.524 -1.9558) (xy -1.524 -1.9558) (xy -1.524 1.9558) (xy 1.524 1.9558)
			)
			(stroke
				(width 0)
				(type default)
			)
			(fill no)
			(layer "B.Fab")
		)
		(pad "1" smd rect
			(at -0.65024 -0.8255 180)
			(size 0.4064 1.2192)
			(layers "B.Cu" "B.Mask" "B.Paste")
			(net "Z50_SSD_A_ACT#")
		)
		(pad "2" smd rect
			(at 0 -0.8255 180)
			(size 0.4064 1.2192)
			(layers "B.Cu" "B.Mask" "B.Paste")
			(net "Z50_SSD_B_ACT#")
		)
		(pad "3" smd rect
			(at 0.65024 -0.8255 180)
			(size 0.4064 1.2192)
			(layers "B.Cu" "B.Mask" "B.Paste")
			(net "GND")
		)
		(pad "4" smd rect
			(at 0.65024 0.8255 180)
			(size 0.4064 1.2192)
			(layers "B.Cu" "B.Mask" "B.Paste")
			(net "Z50_SSD_ACT#")
		)
		(pad "5" smd rect
			(at -0.65024 0.8255 180)
			(size 0.4064 1.2192)
			(layers "B.Cu" "B.Mask" "B.Paste")
			(net "P3V3_DPB")
		)
	)
)
